(kicad_pcb
	(version 20260206)
	(generator "pcbnew")
	(generator_version "10.0")
	(general
		(thickness 1.6)
		(legacy_teardrops no)
	)
	(paper "A4")
	(title_block
		(title "9052_F0T_PDB_Converter_Brick_F_V03_1208_1600_OCP.brd")
		(comment 1 "Grand Teton / footprints 408-414 of 578")
	)
	(layers
		(0 "F.Cu" signal "TOP")
		(4 "In1.Cu" signal "GND")
		(6 "In2.Cu" signal "IN1")
		(8 "In3.Cu" signal "GND1")
		(10 "In4.Cu" signal "VCC")
		(12 "In5.Cu" signal "VCC1")
		(14 "In6.Cu" signal "GND2")
		(16 "In7.Cu" signal "IN2")
		(18 "In8.Cu" signal "GND3")
		(2 "B.Cu" signal "BOTTOM")
		(9 "F.Adhes" user "F.Adhesive")
		(11 "B.Adhes" user "B.Adhesive")
		(13 "F.Paste" user "Package Geometry/Pastemask Top")
		(15 "B.Paste" user "Package Geometry/Pastemask Bottom")
		(5 "F.SilkS" user "Ref Des/Silkscreen Top")
		(7 "B.SilkS" user "Ref Des/Silkscreen Bottom")
		(1 "F.Mask" user "Board Geometry/Soldermask Top")
		(3 "B.Mask" user "Board Geometry/Soldermask Bottom")
		(17 "Dwgs.User" user "User.Drawings")
		(19 "Cmts.User" user "User.Comments")
		(21 "Eco1.User" user "User.Eco1")
		(23 "Eco2.User" user "User.Eco2")
		(25 "Edge.Cuts" user "Board Geometry/Outline")
		(27 "Margin" user)
		(31 "F.CrtYd" user "Package Geometry/Place Bound Top")
		(29 "B.CrtYd" user "Package Geometry/Place Bound Bottom")
		(35 "F.Fab" user "Ref Des/Assembly Top")
		(33 "B.Fab" user "Ref Des/Assembly Bottom")
	)
	(footprint ""
		(layer "B.Cu")
		(at 296.5704 -49.0982 90)
		(property "Reference" "R5890"
			(at 0 0 90)
			(layer "B.SilkS")
			(hide yes)
			(effects
				(font
					(size 1.27 1.27)
				)
				(justify mirror)
			)
		)
		(property "Value" ""
			(at 0 0 90)
			(layer "B.Fab")
			(effects
				(font
					(size 1.27 1.27)
				)
				(justify mirror)
			)
		)
		(duplicate_pad_numbers_are_jumpers no)
		(fp_line
			(start 1.651 -0.8382)
			(end -1.651 -0.8382)
			(stroke
				(width 0.1524)
				(type default)
			)
			(layer "B.SilkS")
		)
		(fp_line
			(start -1.651 -0.8382)
			(end -1.651 0.8382)
			(stroke
				(width 0.1524)
				(type default)
			)
			(layer "B.SilkS")
		)
		(fp_line
			(start 1.651 0.8382)
			(end 1.651 -0.8382)
			(stroke
				(width 0.1524)
				(type default)
			)
			(layer "B.SilkS")
		)
		(fp_line
			(start -1.651 0.8382)
			(end 1.651 0.8382)
			(stroke
				(width 0.1524)
				(type default)
			)
			(layer "B.SilkS")
		)
		(fp_line
			(start 1.559814 -0.7366)
			(end 1.559814 0.7366)
			(stroke
				(width 0.1)
				(type default)
			)
			(layer "B.Fab")
		)
		(fp_line
			(start 1.524 -0.7366)
			(end 1.559814 -0.7366)
			(stroke
				(width 0.1)
				(type default)
			)
			(layer "B.Fab")
		)
		(fp_line
			(start -1.524 -0.7366)
			(end 1.524 -0.7366)
			(stroke
				(width 0.1)
				(type default)
			)
			(layer "B.Fab")
		)
		(fp_line
			(start -1.560576 -0.7366)
			(end -1.524 -0.7366)
			(stroke
				(width 0.1)
				(type default)
			)
			(layer "B.Fab")
		)
		(fp_line
			(start 1.559814 0.7366)
			(end 1.524 0.7366)
			(stroke
				(width 0.1)
				(type default)
			)
			(layer "B.Fab")
		)
		(fp_line
			(start 1.524 0.7366)
			(end -1.524 0.7366)
			(stroke
				(width 0.1)
				(type default)
			)
			(layer "B.Fab")
		)
		(fp_line
			(start -1.524 0.7366)
			(end -1.560576 0.7366)
			(stroke
				(width 0.1)
				(type default)
			)
			(layer "B.Fab")
		)
		(fp_line
			(start -1.560576 0.7366)
			(end -1.560576 -0.7366)
			(stroke
				(width 0.1)
				(type default)
			)
			(layer "B.Fab")
		)
		(pad "1" smd rect
			(at 0.94996 0 90)
			(size 1.1176 1.3716)
			(layers "B.Cu" "B.Mask" "B.Paste")
			(net "P52V_1")
		)
		(pad "2" smd rect
			(at -0.94996 0 90)
			(size 1.1176 1.3716)
			(layers "B.Cu" "B.Mask" "B.Paste")
			(net "P52V_1_R")
		)
	)
	(footprint ""
		(layer "B.Cu")
		(at 229.489 -82.296 -90)
		(property "Reference" "R27"
			(at 0 0 90)
			(layer "B.SilkS")
			(hide yes)
			(effects
				(font
					(size 1.27 1.27)
				)
				(justify mirror)
			)
		)
		(property "Value" ""
			(at 0 0 90)
			(layer "B.Fab")
			(effects
				(font
					(size 1.27 1.27)
				)
				(justify mirror)
			)
		)
		(duplicate_pad_numbers_are_jumpers no)
		(fp_line
			(start -0.7874 0.4064)
			(end 0.7874 0.4064)
			(stroke
				(width 0.1524)
				(type default)
			)
			(layer "B.SilkS")
		)
		(fp_line
			(start 0.7874 0.4064)
			(end 0.7874 -0.4064)
			(stroke
				(width 0.1524)
				(type default)
			)
			(layer "B.SilkS")
		)
		(fp_line
			(start -0.7874 -0.4064)
			(end -0.7874 0.4064)
			(stroke
				(width 0.1524)
				(type default)
			)
			(layer "B.SilkS")
		)
		(fp_line
			(start 0.7874 -0.4064)
			(end -0.7874 -0.4064)
			(stroke
				(width 0.1524)
				(type default)
			)
			(layer "B.SilkS")
		)
		(fp_line
			(start -0.67945 0.3048)
			(end -0.120396 0.3048)
			(stroke
				(width 0.1)
				(type default)
			)
			(layer "B.Fab")
		)
		(fp_line
			(start -0.120396 0.3048)
			(end -0.120396 0.2794)
			(stroke
				(width 0.1)
				(type default)
			)
			(layer "B.Fab")
		)
		(fp_line
			(start 0.12065 0.3048)
			(end 0.67945 0.3048)
			(stroke
				(width 0.1)
				(type default)
			)
			(layer "B.Fab")
		)
		(fp_line
			(start 0.67945 0.3048)
			(end 0.67945 -0.305054)
			(stroke
				(width 0.1)
				(type default)
			)
			(layer "B.Fab")
		)
		(fp_line
			(start -0.120396 0.2794)
			(end 0.12065 0.2794)
			(stroke
				(width 0.1)
				(type default)
			)
			(layer "B.Fab")
		)
		(fp_line
			(start 0.12065 0.2794)
			(end 0.12065 0.3048)
			(stroke
				(width 0.1)
				(type default)
			)
			(layer "B.Fab")
		)
		(fp_line
			(start -0.12065 -0.2794)
			(end -0.12065 -0.3048)
			(stroke
				(width 0.1)
				(type default)
			)
			(layer "B.Fab")
		)
		(fp_line
			(start 0.12065 -0.2794)
			(end -0.12065 -0.2794)
			(stroke
				(width 0.1)
				(type default)
			)
			(layer "B.Fab")
		)
		(fp_line
			(start -0.67945 -0.3048)
			(end -0.67945 0.3048)
			(stroke
				(width 0.1)
				(type default)
			)
			(layer "B.Fab")
		)
		(fp_line
			(start -0.12065 -0.3048)
			(end -0.67945 -0.3048)
			(stroke
				(width 0.1)
				(type default)
			)
			(layer "B.Fab")
		)
		(fp_line
			(start 0.12065 -0.305054)
			(end 0.12065 -0.2794)
			(stroke
				(width 0.1)
				(type default)
			)
			(layer "B.Fab")
		)
		(fp_line
			(start 0.67945 -0.305054)
			(end 0.12065 -0.305054)
			(stroke
				(width 0.1)
				(type default)
			)
			(layer "B.Fab")
		)
		(pad "1" smd circle
			(at 0.40005 0 90)
			(size 0 0)
			(layers "B.Cu" "B.Mask" "B.Paste")
			(net "PWRGD_P3V3_AUX_MB_BUF_R")
		)
		(pad "2" smd circle
			(at -0.40005 0 90)
			(size 0 0)
			(layers "B.Cu" "B.Mask" "B.Paste")
			(net "PWRGD_P3V3_AUX_MB_BUF")
		)
	)
	(footprint ""
		(layer "B.Cu")
		(at 293.4589 -142.52956)
		(property "Reference" ""
			(at 0 0 0)
			(layer "B.SilkS")
			(hide yes)
			(effects
				(font
					(size 1.27 1.27)
				)
				(justify mirror)
			)
		)
		(property "Value" ""
			(at 0 0 0)
			(layer "B.Fab")
			(effects
				(font
					(size 1.27 1.27)
				)
				(justify mirror)
			)
		)
		(duplicate_pad_numbers_are_jumpers no)
		(pad "1" smd circle
			(at 0 0 180)
			(size 0.9906 0.9906)
			(layers "B.Cu" "B.Mask" "B.Paste")
			(net "Net_151")
		)
		(zone
			(layer "B.Cu")
			(hatch none 0.5)
			(connect_pads
				(clearance 0)
			)
			(min_thickness 0.25)
			(keepout
				(tracks not_allowed)
				(vias allowed)
				(pads allowed)
				(copperpour not_allowed)
				(footprints allowed)
			)
			(placement
				(enabled no)
				(sheetname "")
			)
			(fill
				(thermal_gap 0.5)
				(thermal_bridge_width 0.5)
				(island_removal_mode 0)
			)
			(polygon
				(pts
					(arc
						(start 295.0845 -142.52956)
						(mid 291.8333 -142.52956)
						(end 295.0845 -142.52956)
					)
				)
			)
		)
	)
	(footprint ""
		(layer "B.Cu")
		(at 274.3962 -103.759 90)
		(property "Reference" "R5862"
			(at 0 0 90)
			(layer "B.SilkS")
			(hide yes)
			(effects
				(font
					(size 1.27 1.27)
				)
				(justify mirror)
			)
		)
		(property "Value" ""
			(at 0 0 90)
			(layer "B.Fab")
			(effects
				(font
					(size 1.27 1.27)
				)
				(justify mirror)
			)
		)
		(duplicate_pad_numbers_are_jumpers no)
		(fp_line
			(start 0.7874 -0.4064)
			(end -0.7874 -0.4064)
			(stroke
				(width 0.1524)
				(type default)
			)
			(layer "B.SilkS")
		)
		(fp_line
			(start -0.7874 -0.4064)
			(end -0.7874 0.4064)
			(stroke
				(width 0.1524)
				(type default)
			)
			(layer "B.SilkS")
		)
		(fp_line
			(start 0.7874 0.4064)
			(end 0.7874 -0.4064)
			(stroke
				(width 0.1524)
				(type default)
			)
			(layer "B.SilkS")
		)
		(fp_line
			(start -0.7874 0.4064)
			(end 0.7874 0.4064)
			(stroke
				(width 0.1524)
				(type default)
			)
			(layer "B.SilkS")
		)
		(fp_line
			(start 0.67945 -0.305054)
			(end 0.12065 -0.305054)
			(stroke
				(width 0.1)
				(type default)
			)
			(layer "B.Fab")
		)
		(fp_line
			(start 0.12065 -0.305054)
			(end 0.12065 -0.2794)
			(stroke
				(width 0.1)
				(type default)
			)
			(layer "B.Fab")
		)
		(fp_line
			(start -0.12065 -0.3048)
			(end -0.67945 -0.3048)
			(stroke
				(width 0.1)
				(type default)
			)
			(layer "B.Fab")
		)
		(fp_line
			(start -0.67945 -0.3048)
			(end -0.67945 0.3048)
			(stroke
				(width 0.1)
				(type default)
			)
			(layer "B.Fab")
		)
		(fp_line
			(start 0.12065 -0.2794)
			(end -0.12065 -0.2794)
			(stroke
				(width 0.1)
				(type default)
			)
			(layer "B.Fab")
		)
		(fp_line
			(start -0.12065 -0.2794)
			(end -0.12065 -0.3048)
			(stroke
				(width 0.1)
				(type default)
			)
			(layer "B.Fab")
		)
		(fp_line
			(start 0.12065 0.2794)
			(end 0.12065 0.3048)
			(stroke
				(width 0.1)
				(type default)
			)
			(layer "B.Fab")
		)
		(fp_line
			(start -0.120396 0.2794)
			(end 0.12065 0.2794)
			(stroke
				(width 0.1)
				(type default)
			)
			(layer "B.Fab")
		)
		(fp_line
			(start 0.67945 0.3048)
			(end 0.67945 -0.305054)
			(stroke
				(width 0.1)
				(type default)
			)
			(layer "B.Fab")
		)
		(fp_line
			(start 0.12065 0.3048)
			(end 0.67945 0.3048)
			(stroke
				(width 0.1)
				(type default)
			)
			(layer "B.Fab")
		)
		(fp_line
			(start -0.120396 0.3048)
			(end -0.120396 0.2794)
			(stroke
				(width 0.1)
				(type default)
			)
			(layer "B.Fab")
		)
		(fp_line
			(start -0.67945 0.3048)
			(end -0.120396 0.3048)
			(stroke
				(width 0.1)
				(type default)
			)
			(layer "B.Fab")
		)
		(pad "1" smd circle
			(at 0.40005 0 270)
			(size 0 0)
			(layers "B.Cu" "B.Mask" "B.Paste")
			(net "P52V_HS1_GATE1_R")
		)
		(pad "2" smd circle
			(at -0.40005 0 270)
			(size 0 0)
			(layers "B.Cu" "B.Mask" "B.Paste")
			(net "P52V_HS1_4287_GATE_R")
		)
	)
	(footprint ""
		(layer "B.Cu")
		(at 189.611 -91.821)
		(property "Reference" "C48"
			(at 0 0 0)
			(layer "B.SilkS")
			(hide yes)
			(effects
				(font
					(size 1.27 1.27)
				)
				(justify mirror)
			)
		)
		(property "Value" ""
			(at 0 0 0)
			(layer "B.Fab")
			(effects
				(font
					(size 1.27 1.27)
				)
				(justify mirror)
			)
		)
		(duplicate_pad_numbers_are_jumpers no)
		(fp_line
			(start -0.7874 -0.4064)
			(end -0.7874 0.4064)
			(stroke
				(width 0.1524)
				(type default)
			)
			(layer "B.SilkS")
		)
		(fp_line
			(start -0.7874 0.4064)
			(end 0.7874 0.4064)
			(stroke
				(width 0.1524)
				(type default)
			)
			(layer "B.SilkS")
		)
		(fp_line
			(start 0.7874 -0.4064)
			(end -0.7874 -0.4064)
			(stroke
				(width 0.1524)
				(type default)
			)
			(layer "B.SilkS")
		)
		(fp_line
			(start 0.7874 0.4064)
			(end 0.7874 -0.4064)
			(stroke
				(width 0.1524)
				(type default)
			)
			(layer "B.SilkS")
		)
		(fp_line
			(start -0.67945 -0.3048)
			(end -0.67945 0.3048)
			(stroke
				(width 0.1)
				(type default)
			)
			(layer "B.Fab")
		)
		(fp_line
			(start -0.67945 0.3048)
			(end -0.120396 0.3048)
			(stroke
				(width 0.1)
				(type default)
			)
			(layer "B.Fab")
		)
		(fp_line
			(start -0.12065 -0.3048)
			(end -0.67945 -0.3048)
			(stroke
				(width 0.1)
				(type default)
			)
			(layer "B.Fab")
		)
		(fp_line
			(start -0.12065 -0.2794)
			(end -0.12065 -0.3048)
			(stroke
				(width 0.1)
				(type default)
			)
			(layer "B.Fab")
		)
		(fp_line
			(start -0.120396 0.2794)
			(end 0.12065 0.2794)
			(stroke
				(width 0.1)
				(type default)
			)
			(layer "B.Fab")
		)
		(fp_line
			(start -0.120396 0.3048)
			(end -0.120396 0.2794)
			(stroke
				(width 0.1)
				(type default)
			)
			(layer "B.Fab")
		)
		(fp_line
			(start 0.12065 -0.305054)
			(end 0.12065 -0.2794)
			(stroke
				(width 0.1)
				(type default)
			)
			(layer "B.Fab")
		)
		(fp_line
			(start 0.12065 -0.2794)
			(end -0.12065 -0.2794)
			(stroke
				(width 0.1)
				(type default)
			)
			(layer "B.Fab")
		)
		(fp_line
			(start 0.12065 0.2794)
			(end 0.12065 0.3048)
			(stroke
				(width 0.1)
				(type default)
			)
			(layer "B.Fab")
		)
		(fp_line
			(start 0.12065 0.3048)
			(end 0.67945 0.3048)
			(stroke
				(width 0.1)
				(type default)
			)
			(layer "B.Fab")
		)
		(fp_line
			(start 0.67945 -0.305054)
			(end 0.12065 -0.305054)
			(stroke
				(width 0.1)
				(type default)
			)
			(layer "B.Fab")
		)
		(fp_line
			(start 0.67945 0.3048)
			(end 0.67945 -0.305054)
			(stroke
				(width 0.1)
				(type default)
			)
			(layer "B.Fab")
		)
		(pad "1" smd circle
			(at 0.40005 0 180)
			(size 0 0)
			(layers "B.Cu" "B.Mask" "B.Paste")
			(net "P3V3_AUX")
		)
		(pad "2" smd circle
			(at -0.40005 0 180)
			(size 0 0)
			(layers "B.Cu" "B.Mask" "B.Paste")
			(net "GND")
		)
	)
	(footprint ""
		(layer "B.Cu")
		(at 277.876 -101.981)
		(property "Reference" "PR26"
			(at 0 0 0)
			(layer "B.SilkS")
			(hide yes)
			(effects
				(font
					(size 1.27 1.27)
				)
				(justify mirror)
			)
		)
		(property "Value" ""
			(at 0 0 0)
			(layer "B.Fab")
			(effects
				(font
					(size 1.27 1.27)
				)
				(justify mirror)
			)
		)
		(duplicate_pad_numbers_are_jumpers no)
		(fp_line
			(start -0.7874 -0.4064)
			(end -0.7874 0.4064)
			(stroke
				(width 0.1524)
				(type default)
			)
			(layer "B.SilkS")
		)
		(fp_line
			(start -0.7874 0.4064)
			(end 0.7874 0.4064)
			(stroke
				(width 0.1524)
				(type default)
			)
			(layer "B.SilkS")
		)
		(fp_line
			(start 0.7874 -0.4064)
			(end -0.7874 -0.4064)
			(stroke
				(width 0.1524)
				(type default)
			)
			(layer "B.SilkS")
		)
		(fp_line
			(start 0.7874 0.4064)
			(end 0.7874 -0.4064)
			(stroke
				(width 0.1524)
				(type default)
			)
			(layer "B.SilkS")
		)
		(fp_line
			(start -0.67945 -0.3048)
			(end -0.67945 0.3048)
			(stroke
				(width 0.1)
				(type default)
			)
			(layer "B.Fab")
		)
		(fp_line
			(start -0.67945 0.3048)
			(end -0.120396 0.3048)
			(stroke
				(width 0.1)
				(type default)
			)
			(layer "B.Fab")
		)
		(fp_line
			(start -0.12065 -0.3048)
			(end -0.67945 -0.3048)
			(stroke
				(width 0.1)
				(type default)
			)
			(layer "B.Fab")
		)
		(fp_line
			(start -0.12065 -0.2794)
			(end -0.12065 -0.3048)
			(stroke
				(width 0.1)
				(type default)
			)
			(layer "B.Fab")
		)
		(fp_line
			(start -0.120396 0.2794)
			(end 0.12065 0.2794)
			(stroke
				(width 0.1)
				(type default)
			)
			(layer "B.Fab")
		)
		(fp_line
			(start -0.120396 0.3048)
			(end -0.120396 0.2794)
			(stroke
				(width 0.1)
				(type default)
			)
			(layer "B.Fab")
		)
		(fp_line
			(start 0.12065 -0.305054)
			(end 0.12065 -0.2794)
			(stroke
				(width 0.1)
				(type default)
			)
			(layer "B.Fab")
		)
		(fp_line
			(start 0.12065 -0.2794)
			(end -0.12065 -0.2794)
			(stroke
				(width 0.1)
				(type default)
			)
			(layer "B.Fab")
		)
		(fp_line
			(start 0.12065 0.2794)
			(end 0.12065 0.3048)
			(stroke
				(width 0.1)
				(type default)
			)
			(layer "B.Fab")
		)
		(fp_line
			(start 0.12065 0.3048)
			(end 0.67945 0.3048)
			(stroke
				(width 0.1)
				(type default)
			)
			(layer "B.Fab")
		)
		(fp_line
			(start 0.67945 -0.305054)
			(end 0.12065 -0.305054)
			(stroke
				(width 0.1)
				(type default)
			)
			(layer "B.Fab")
		)
		(fp_line
			(start 0.67945 0.3048)
			(end 0.67945 -0.305054)
			(stroke
				(width 0.1)
				(type default)
			)
			(layer "B.Fab")
		)
		(pad "1" smd rect
			(at 0.40005 0)
			(size 0.4572 0.508)
			(layers "B.Cu" "B.Mask" "B.Paste")
			(net "P52V_HS1_GATE_R1")
		)
		(pad "2" smd rect
			(at -0.40005 0)
			(size 0.4572 0.508)
			(layers "B.Cu" "B.Mask" "B.Paste")
			(net "P52V_HS1_4287_GATE_R")
		)
	)
	(footprint ""
		(layer "B.Cu")
		(at 208.534 -69.723 -90)
		(property "Reference" "R118"
			(at 0 0 90)
			(layer "B.SilkS")
			(hide yes)
			(effects
				(font
					(size 1.27 1.27)
				)
				(justify mirror)
			)
		)
		(property "Value" ""
			(at 0 0 90)
			(layer "B.Fab")
			(effects
				(font
					(size 1.27 1.27)
				)
				(justify mirror)
			)
		)
		(duplicate_pad_numbers_are_jumpers no)
		(fp_line
			(start -0.7874 0.4064)
			(end 0.7874 0.4064)
			(stroke
				(width 0.1524)
				(type default)
			)
			(layer "B.SilkS")
		)
		(fp_line
			(start 0.7874 0.4064)
			(end 0.7874 -0.4064)
			(stroke
				(width 0.1524)
				(type default)
			)
			(layer "B.SilkS")
		)
		(fp_line
			(start -0.7874 -0.4064)
			(end -0.7874 0.4064)
			(stroke
				(width 0.1524)
				(type default)
			)
			(layer "B.SilkS")
		)
		(fp_line
			(start 0.7874 -0.4064)
			(end -0.7874 -0.4064)
			(stroke
				(width 0.1524)
				(type default)
			)
			(layer "B.SilkS")
		)
		(fp_line
			(start -0.67945 0.3048)
			(end -0.120396 0.3048)
			(stroke
				(width 0.1)
				(type default)
			)
			(layer "B.Fab")
		)
		(fp_line
			(start -0.120396 0.3048)
			(end -0.120396 0.2794)
			(stroke
				(width 0.1)
				(type default)
			)
			(layer "B.Fab")
		)
		(fp_line
			(start 0.12065 0.3048)
			(end 0.67945 0.3048)
			(stroke
				(width 0.1)
				(type default)
			)
			(layer "B.Fab")
		)
		(fp_line
			(start 0.67945 0.3048)
			(end 0.67945 -0.305054)
			(stroke
				(width 0.1)
				(type default)
			)
			(layer "B.Fab")
		)
		(fp_line
			(start -0.120396 0.2794)
			(end 0.12065 0.2794)
			(stroke
				(width 0.1)
				(type default)
			)
			(layer "B.Fab")
		)
		(fp_line
			(start 0.12065 0.2794)
			(end 0.12065 0.3048)
			(stroke
				(width 0.1)
				(type default)
			)
			(layer "B.Fab")
		)
		(fp_line
			(start -0.12065 -0.2794)
			(end -0.12065 -0.3048)
			(stroke
				(width 0.1)
				(type default)
			)
			(layer "B.Fab")
		)
		(fp_line
			(start 0.12065 -0.2794)
			(end -0.12065 -0.2794)
			(stroke
				(width 0.1)
				(type default)
			)
			(layer "B.Fab")
		)
		(fp_line
			(start -0.67945 -0.3048)
			(end -0.67945 0.3048)
			(stroke
				(width 0.1)
				(type default)
			)
			(layer "B.Fab")
		)
		(fp_line
			(start -0.12065 -0.3048)
			(end -0.67945 -0.3048)
			(stroke
				(width 0.1)
				(type default)
			)
			(layer "B.Fab")
		)
		(fp_line
			(start 0.12065 -0.305054)
			(end 0.12065 -0.2794)
			(stroke
				(width 0.1)
				(type default)
			)
			(layer "B.Fab")
		)
		(fp_line
			(start 0.67945 -0.305054)
			(end 0.12065 -0.305054)
			(stroke
				(width 0.1)
				(type default)
			)
			(layer "B.Fab")
		)
		(pad "1" smd circle
			(at 0.40005 0 90)
			(size 0 0)
			(layers "B.Cu" "B.Mask" "B.Paste")
			(net "SMB_VPDB_MISC_SCL")
		)
		(pad "2" smd circle
			(at -0.40005 0 90)
			(size 0 0)
			(layers "B.Cu" "B.Mask" "B.Paste")
			(net "SMB_VPDB_IOEXP_SCL")
		)
	)
)
